# S9S_MB_2U (Grand Teton) — schematic netlist excerpt (pin names and nets, part order shuffled) for the footprints in the layout excerpt that follows; sources: Cadence DE-HDL packaged netlist, KiCad conversion of 03242023_DA0F0TMBIJ0_F0T_Motherboard_J_brd_V01_OCP.brd

J23  SCONN288_ADR50017P130CC  SCONN288_ADR50017-P130CC IO  pkg DDR288S_1-1VXB  page 104
  VIN_BULK0  = P12V_S3_AUX_CPU1_NVDIMM
  RFU0  = TP_CHD_CPU1_DIMM1_FRU_0
  VIN_MGMT  = P3V3_AUX
  HSCL  = I3C_SPD_DDRABCD_CPU1_LVC1_SCL_6
  HSDA  = I3C_SPD_DDRABCD_CPU1_LVC1_SDA
  VSS0  = GND
  DQ0_A  = M_D_CPU1_SA_DQ<0>
  VSS1  = GND
  DQ1_A  = M_D_CPU1_SA_DQ<1>
  VSS2  = GND
  DQS0_A_T  = M_D_CPU1_SA_DQS_DP<0>
  DQS0_A_C  = M_D_CPU1_SA_DQS_DN<0>
  VSS3  = GND
  DQ4_A  = M_D_CPU1_SA_DQ<4>
  VSS4  = GND
  DQ5_A  = M_D_CPU1_SA_DQ<5>
  VSS5  = GND
  DQ8_A  = M_D_CPU1_SA_DQ<8>
  VSS6  = GND
  DQ9_A  = M_D_CPU1_SA_DQ<9>
  VSS7  = GND
  DQS1_A_T  = M_D_CPU1_SA_DQS_DP<1>
  DQS1_A_C  = M_D_CPU1_SA_DQS_DN<1>
  VSS8  = GND
  DQ12_A  = M_D_CPU1_SA_DQ<12>
  VSS9  = GND
  DQ13_A  = M_D_CPU1_SA_DQ<13>
  VSS10  = GND
  DQ16_A  = M_D_CPU1_SA_DQ<16>
  VSS11  = GND
  DQ17_A  = M_D_CPU1_SA_DQ<17>
  VSS12  = GND
  DQS2_A_T  = M_D_CPU1_SA_DQS_DP<2>
  DQS2_A_C  = M_D_CPU1_SA_DQS_DN<2>
  VSS13  = GND
  DQ20_A  = M_D_CPU1_SA_DQ<20>
  VSS14  = GND
  DQ21_A  = M_D_CPU1_SA_DQ<21>
  VSS15  = GND
  DQ24_A  = M_D_CPU1_SA_DQ<24>
  VSS16  = GND
  DQ25_A  = M_D_CPU1_SA_DQ<25>
  VSS17  = GND
  DQS3_A_T  = M_D_CPU1_SA_DQS_DP<3>
  DQS3_A_C  = M_D_CPU1_SA_DQS_DN<3>
  VSS18  = GND
  DQ28_A  = M_D_CPU1_SA_DQ<28>
  VSS19  = GND
  DQ29_A  = M_D_CPU1_SA_DQ<29>
  VSS20  = GND
  CB0_A  = M_D_CPU1_SA_CB<0>
  VSS21  = GND
  CB1_A  = M_D_CPU1_SA_CB<1>
  VSS22  = GND
  DQS4_A_T  = M_D_CPU1_SA_DQS_DP<4>
  DQS4_A_C  = M_D_CPU1_SA_DQS_DN<4>
  VSS23  = GND
  CB4_A  = M_D_CPU1_SA_CB<4>
  VSS24  = GND
  CB5_A  = M_D_CPU1_SA_CB<5>
  VSS25  = GND
  ALERT_N  = M_D_CPU1_ALERT_N
  VSS26  = GND
  CS0_A_N  = M_D_CPU1_SA_CS_N<0>
  VSS27  = GND
  CA0_A  = M_D_CPU1_SA_CA<0>
  VSS28  = GND
  CA2_A  = M_D_CPU1_SA_CA<2>
  VSS29  = GND
  CA4_A  = M_D_CPU1_SA_CA<4>
  VSS30  = GND
  CA6_A  = M_D_CPU1_SA_CA<6>
  VSS31  = GND
  PAR_A  = M_D_CPU1_SA_PAR
  VSS32  = GND
  CA0_B  = M_D_CPU1_SB_CA<0>
  VSS33  = GND
  CA2_B  = M_D_CPU1_SB_CA<2>
  VSS34  = GND
  CA4_B  = M_D_CPU1_SB_CA<4>
  VSS35  = GND
  CA6_B  = M_D_CPU1_SB_CA<6>
  VSS36  = GND
  CS0_B_N  = M_D_CPU1_SB_CS_N<0>
  VSS37  = GND
  \lbd||rsp_a_n\  = M_D_CPU1_SA_RSP<0>
  \lbs||rsp_b_n\  = M_D_CPU1_SB_RSP<0>
  VSS38  = GND
  CB4_B  = M_D_CPU1_SB_CB<4>
  VSS39  = GND
  CB5_B  = M_D_CPU1_SB_CB<5>
  VSS40  = GND
  \dqs9_b_t||tdqs9_b_t||dbi4_b_n\  = M_D_CPU1_SB_DQS_DP<9>
  \dqs9_b_c||tdqs9_b_c\  = M_D_CPU1_SB_DQS_DN<9>
  VSS41  = GND
  CB0_B  = M_D_CPU1_SB_CB<0>
  VSS42  = GND
  CB1_B  = M_D_CPU1_SB_CB<1>
  VSS43  = GND
  DQ0_B  = M_D_CPU1_SB_DQ<0>
  VSS44  = GND
  DQ1_B  = M_D_CPU1_SB_DQ<1>
  VSS45  = GND
  DQS0_B_T  = M_D_CPU1_SB_DQS_DP<0>
  DQS0_B_C  = M_D_CPU1_SB_DQS_DN<0>
  VSS46  = GND
  DQ4_B  = M_D_CPU1_SB_DQ<4>
  VSS47  = GND
  DQ5_B  = M_D_CPU1_SB_DQ<5>
  VSS48  = GND
  DQ8_B  = M_D_CPU1_SB_DQ<8>
  VSS49  = GND
  DQ9_B  = M_D_CPU1_SB_DQ<9>
  VSS50  = GND
  DQS1_B_T  = M_D_CPU1_SB_DQS_DP<1>
  DQS1_B_C  = M_D_CPU1_SB_DQS_DN<1>
  VSS51  = GND
  DQ12_B  = M_D_CPU1_SB_DQ<12>
  VSS52  = GND
  DQ13_B  = M_D_CPU1_SB_DQ<13>
  VSS53  = GND
  DQ16_B  = M_D_CPU1_SB_DQ<16>
  VSS54  = GND
  DQ17_B  = M_D_CPU1_SB_DQ<17>
  VSS55  = GND
  DQS2_B_T  = M_D_CPU1_SB_DQS_DP<2>
  DQS2_B_C  = M_D_CPU1_SB_DQS_DN<2>
  VSS56  = GND
  DQ20_B  = M_D_CPU1_SB_DQ<20>
  VSS57  = GND
  DQ21_B  = M_D_CPU1_SB_DQ<21>
  VSS58  = GND
  DQ24_B  = M_D_CPU1_SB_DQ<24>
  VSS59  = GND
  DQ25_B  = M_D_CPU1_SB_DQ<25>
  VSS60  = GND
  DQS3_B_T  = M_D_CPU1_SB_DQS_DP<3>
  DQS3_B_C  = M_D_CPU1_SB_DQS_DN<3>
  VSS61  = GND
  DQ28_B  = M_D_CPU1_SB_DQ<28>
  VSS62  = GND
  DQ29_B  = M_D_CPU1_SB_DQ<29>
  VSS63  = GND
  RFU1  = TP_CHD_CPU1_DIMM1_FRU_1
  VIN_BULK1  = P12V_S3_AUX_CPU1_NVDIMM
  VIN_BULK2  = P12V_S3_AUX_CPU1_NVDIMM
  \pwr_good||fail_n\  = PWRGD_CHD_CPU1_DIMM1
  HSA  = PD_CHD_CPU1_DIMM1_SAA
  RFU2  = TP_CHD_CPU1_DIMM1_FRU_2
  RFU3  = TP_CHD_CPU1_DIMM1_FRU_3
  VSS64  = GND
  DQ2_A  = M_D_CPU1_SA_DQ<2>
  VSS65  = GND
  DQ3_A  = M_D_CPU1_SA_DQ<3>
  VSS66  = GND
  \dqs5_a_c||tdqs5_a_c||dqs5_a_t||tdqs5_a_t\  = M_D_CPU1_SA_DQS_DN<5>
  \dqs5_a_t||tdqs5_a_t\  = M_D_CPU1_SA_DQS_DP<5>
  VSS67  = GND
  DQ6_A  = M_D_CPU1_SA_DQ<6>
  VSS68  = GND
  DQ7_A  = M_D_CPU1_SA_DQ<7>
  VSS69  = GND
  DQ10_A  = M_D_CPU1_SA_DQ<10>
  VSS70  = GND
  DQ11_A  = M_D_CPU1_SA_DQ<11>
  VSS71  = GND
  \dqs6_a_c||tdqs6_a_c||dqs6_a_t||tdqs6_a_t\  = M_D_CPU1_SA_DQS_DN<6>
  \dqs6_a_t||tdqs6_a_t\  = M_D_CPU1_SA_DQS_DP<6>
  VSS72  = GND
  DQ14_A  = M_D_CPU1_SA_DQ<14>
  VSS73  = GND
  DQ15_A  = M_D_CPU1_SA_DQ<15>
  VSS74  = GND
  DQ18_A  = M_D_CPU1_SA_DQ<18>
  VSS75  = GND
  DQ19_A  = M_D_CPU1_SA_DQ<19>
  VSS76  = GND
  \dqs7_a_c||tdqs7_a_c\  = M_D_CPU1_SA_DQS_DN<7>
  \dqs7_a_t||tdqs7_a_t\  = M_D_CPU1_SA_DQS_DP<7>
  VSS77  = GND
  DQ22_A  = M_D_CPU1_SA_DQ<22>
  VSS78  = GND
  DQ23_A  = M_D_CPU1_SA_DQ<23>
  VSS79  = GND
  DQ26_A  = M_D_CPU1_SA_DQ<26>
  VSS80  = GND
  DQ27_A  = M_D_CPU1_SA_DQ<27>
  VSS81  = GND
  \dqs8_a_c||tdqs8_a_c\  = M_D_CPU1_SA_DQS_DN<8>
  \dqs8_a_t||tdqs8_a_t\  = M_D_CPU1_SA_DQS_DP<8>
  VSS82  = GND
  DQ30_A  = M_D_CPU1_SA_DQ<30>
  VSS83  = GND
  DQ31_A  = M_D_CPU1_SA_DQ<31>
  VSS84  = GND
  CB2_A  = M_D_CPU1_SA_CB<2>
  VSS85  = GND
  CB3_A  = M_D_CPU1_SA_CB<3>
  VSS86  = GND
  \dqs9_a_c||tdqs9_a_c\  = M_D_CPU1_SA_DQS_DN<9>
  \dqs9_a_t||tdqs9_a_t\  = M_D_CPU1_SA_DQS_DP<9>
  VSS87  = GND
  CB6_A  = M_D_CPU1_SA_CB<6>
  VSS88  = GND
  CB7_A  = M_D_CPU1_SA_CB<7>
  VSS89  = GND
  RESET_N  = RST_M_CD_CPU1_FPGA_N
  VSS90  = GND
  CS1_A_N  = M_D_CPU1_SA_CS_N<1>
  VSS91  = GND
  CA1_A  = M_D_CPU1_SA_CA<1>
  VSS92  = GND
  CA3_A  = M_D_CPU1_SA_CA<3>
  VSS93  = GND
  CA5_A  = M_D_CPU1_SA_CA<5>
  VSS94  = GND
  CK_T  = M_D_CPU1_CLK_DP<0>
  CK_C  = M_D_CPU1_CLK_DN<0>
  VSS95  = GND
  RFU4  = TP_CHD_CPU1_DIMM1_FRU_4
  CA1_B  = M_D_CPU1_SB_CA<1>
  VSS96  = GND
  CA3_B  = M_D_CPU1_SB_CA<3>
  VSS97  = GND
  CA5_B  = M_D_CPU1_SB_CA<5>
  VSS98  = GND
  PAR_B  = M_D_CPU1_SB_PAR
  VSS99  = GND
  CS1_B_N  = M_D_CPU1_SB_CS_N<1>
  VSS100  = GND
  RFU5  = TP_CHD_CPU1_DIMM1_FRU_5
  RFU6  = TP_CHD_CPU1_DIMM1_FRU_6
  VSS101  = GND
  CB6_B  = M_D_CPU1_SB_CB<6>
  VSS102  = GND
  CB7_B  = M_D_CPU1_SB_CB<7>
  VSS103  = GND
  DQS4_B_C  = M_D_CPU1_SB_DQS_DN<4>
  DQS4_B_T  = M_D_CPU1_SB_DQS_DP<4>
  VSS104  = GND
  CB2_B  = M_D_CPU1_SB_CB<2>
  VSS105  = GND
  CB3_B  = M_D_CPU1_SB_CB<3>
  VSS106  = GND
  DQ2_B  = M_D_CPU1_SB_DQ<2>
  VSS107  = GND
  DQ3_B  = M_D_CPU1_SB_DQ<3>
  VSS108  = GND
  \dqs5_b_c||tdqs5_b_c\  = M_D_CPU1_SB_DQS_DN<5>
  \dqs5_b_t||tdqs5_b_t\  = M_D_CPU1_SB_DQS_DP<5>
  VSS109  = GND
  DQ6_B  = M_D_CPU1_SB_DQ<6>
  VSS110  = GND
  DQ7_B  = M_D_CPU1_SB_DQ<7>
  VSS111  = GND
  DQ10_B  = M_D_CPU1_SB_DQ<10>
  VSS112  = GND
  DQ11_B  = M_D_CPU1_SB_DQ<11>
  VSS113  = GND
  \dqs6_b_c||tdqs6_b_c\  = M_D_CPU1_SB_DQS_DN<6>
  \dqs6_b_t||tdqs6_b_t\  = M_D_CPU1_SB_DQS_DP<6>
  VSS114  = GND
  DQ14_B  = M_D_CPU1_SB_DQ<14>
  VSS115  = GND
  DQ15_B  = M_D_CPU1_SB_DQ<15>
  VSS116  = GND
  DQ18_B  = M_D_CPU1_SB_DQ<18>
  VSS117  = GND
  DQ19_B  = M_D_CPU1_SB_DQ<19>
  VSS118  = GND
  \dqs7_b_c||tdqs7_b_c\  = M_D_CPU1_SB_DQS_DN<7>
  \dqs7_b_t||tdqs7_b_t\  = M_D_CPU1_SB_DQS_DP<7>
  VSS119  = GND
  DQ22_B  = M_D_CPU1_SB_DQ<22>
  VSS120  = GND
  DQ23_B  = M_D_CPU1_SB_DQ<23>
  VSS121  = GND
  DQ26_B  = M_D_CPU1_SB_DQ<26>
  VSS122  = GND
  DQ27_B  = M_D_CPU1_SB_DQ<27>
  VSS123  = GND
  \dqs8_b_c||tdqs8_b_c\  = M_D_CPU1_SB_DQS_DN<8>
  \dqs8_b_t||tdqs8_b_t\  = M_D_CPU1_SB_DQS_DP<8>
  VSS124  = GND
  DQ30_B  = M_D_CPU1_SB_DQ<30>
  VSS125  = GND
  DQ31_B  = M_D_CPU1_SB_DQ<31>
  VSS126  = GND
  G1  = GND
  G2  = GND
  G3  = GND

(kicad_pcb
	(version 20260206)
	(generator "pcbnew")
	(generator_version "10.0")
	(general
		(thickness 1.6)
		(legacy_teardrops no)
	)
	(paper "A4")
	(title_block
		(title "03242023_DA0F0TMBIJ0_F0T_Motherboard_J_brd_V01_OCP.brd")
		(comment 1 "Grand Teton / footprint 3586 of 6105 (J23), pads 275-291 of 291")
	)
	(layers
		(0 "F.Cu" signal "TOP")
		(4 "In1.Cu" signal "GND")
		(6 "In2.Cu" signal "IN1")
		(8 "In3.Cu" signal "GND1")
		(10 "In4.Cu" signal "IN2")
		(12 "In5.Cu" signal "GND2")
		(14 "In6.Cu" signal "IN3")
		(16 "In7.Cu" signal "GND3")
		(18 "In8.Cu" signal "VCC")
		(20 "In9.Cu" signal "VCC1")
		(22 "In10.Cu" signal "GND4")
		(24 "In11.Cu" signal "IN4")
		(26 "In12.Cu" signal "GND5")
		(28 "In13.Cu" signal "IN5")
		(30 "In14.Cu" signal "GND6")
		(32 "In15.Cu" signal "IN6")
		(34 "In16.Cu" signal "GND7")
		(2 "B.Cu" signal "BOTTOM")
		(9 "F.Adhes" user "F.Adhesive")
		(11 "B.Adhes" user "B.Adhesive")
		(13 "F.Paste" user "Package Geometry/Pastemask Top")
		(15 "B.Paste" user "Package Geometry/Pastemask Bottom")
		(5 "F.SilkS" user "Ref Des/Silkscreen Top")
		(7 "B.SilkS" user "Ref Des/Silkscreen Bottom")
		(1 "F.Mask" user "Board Geometry/Soldermask Top")
		(3 "B.Mask" user "Board Geometry/Soldermask Bottom")
		(17 "Dwgs.User" user "User.Drawings")
		(19 "Cmts.User" user "User.Comments")
		(21 "Eco1.User" user "User.Eco1")
		(23 "Eco2.User" user "User.Eco2")
		(25 "Edge.Cuts" user "Board Geometry/Outline")
		(27 "Margin" user)
		(31 "F.CrtYd" user "Package Geometry/Place Bound Top")
		(29 "B.CrtYd" user "Package Geometry/Place Bound Bottom")
		(35 "F.Fab" user "Ref Des/Assembly Top")
		(33 "B.Fab" user "Ref Des/Assembly Bottom")
	)
	(footprint ""
		(layer "F.Cu")
		(at 10.19048 -258.091686)
		(property "Reference" "J23"
			(at -5.69468 -80.480408 0)
			(unlocked yes)
			(layer "F.SilkS")
			(effects
				(font
					(size 0.7874 0.5842)
					(thickness 0.1524)
				)
				(justify left)
			)
		)
		(property "Value" ""
			(at 0 0 0)
			(layer "F.Fab")
			(effects
				(font
					(size 1.27 1.27)
				)
			)
		)
		(duplicate_pad_numbers_are_jumpers no)
		(pad "275" smd rect
			(at 2.050034 52.274978 270)
			(size 0.519938 1.4986)
			(layers "F.Cu" "F.Mask" "F.Paste")
			(net "GND")
		)
		(pad "276" smd rect
			(at 2.050034 53.125116 270)
			(size 0.519938 1.4986)
			(layers "F.Cu" "F.Mask" "F.Paste")
			(net "M_D_CPU1_SB_DQ<23>")
		)
		(pad "277" smd rect
			(at 2.050034 53.975 270)
			(size 0.519938 1.4986)
			(layers "F.Cu" "F.Mask" "F.Paste")
			(net "GND")
		)
		(pad "278" smd rect
			(at 2.050034 54.824884 270)
			(size 0.519938 1.4986)
			(layers "F.Cu" "F.Mask" "F.Paste")
			(net "M_D_CPU1_SB_DQ<26>")
		)
		(pad "279" smd rect
			(at 2.050034 55.675022 270)
			(size 0.519938 1.4986)
			(layers "F.Cu" "F.Mask" "F.Paste")
			(net "GND")
		)
		(pad "280" smd rect
			(at 2.050034 56.524906 270)
			(size 0.519938 1.4986)
			(layers "F.Cu" "F.Mask" "F.Paste")
			(net "M_D_CPU1_SB_DQ<27>")
		)
		(pad "281" smd rect
			(at 2.050034 57.375044 270)
			(size 0.519938 1.4986)
			(layers "F.Cu" "F.Mask" "F.Paste")
			(net "GND")
		)
		(pad "282" smd rect
			(at 2.050034 58.224928 270)
			(size 0.519938 1.4986)
			(layers "F.Cu" "F.Mask" "F.Paste")
			(net "M_D_CPU1_SB_DQS_DN<8>")
		)
		(pad "283" smd rect
			(at 2.050034 59.075066 270)
			(size 0.519938 1.4986)
			(layers "F.Cu" "F.Mask" "F.Paste")
			(net "M_D_CPU1_SB_DQS_DP<8>")
		)
		(pad "284" smd rect
			(at 2.050034 59.92495 270)
			(size 0.519938 1.4986)
			(layers "F.Cu" "F.Mask" "F.Paste")
			(net "GND")
		)
		(pad "285" smd rect
			(at 2.050034 60.775088 270)
			(size 0.519938 1.4986)
			(layers "F.Cu" "F.Mask" "F.Paste")
			(net "M_D_CPU1_SB_DQ<30>")
		)
		(pad "286" smd rect
			(at 2.050034 61.624972 270)
			(size 0.519938 1.4986)
			(layers "F.Cu" "F.Mask" "F.Paste")
			(net "GND")
		)
		(pad "287" smd rect
			(at 2.050034 62.47511 270)
			(size 0.519938 1.4986)
			(layers "F.Cu" "F.Mask" "F.Paste")
			(net "M_D_CPU1_SB_DQ<31>")
		)
		(pad "288" smd rect
			(at 2.050034 63.324994 270)
			(size 0.519938 1.4986)
			(layers "F.Cu" "F.Mask" "F.Paste")
			(net "GND")
		)
		(pad "G1" thru_hole oval
			(at 0 -68.97497)
			(size 2.8194 1.5748)
			(drill oval 2.4384 1.1938)
			(layers "*.Cu" "*.Mask")
			(remove_unused_layers no)
			(net "GND")
			(clearance 0.127)
			(thermal_gap 0.127)
		)
		(pad "G2" thru_hole oval
			(at 0 3.875024)
			(size 2.8194 1.5748)
			(drill oval 2.4384 1.1938)
			(layers "*.Cu" "*.Mask")
			(remove_unused_layers no)
			(net "GND")
			(clearance 0.127)
			(thermal_gap 0.127)
		)
		(pad "G3" thru_hole oval
			(at 0 68.97497)
			(size 2.8194 1.5748)
			(drill oval 2.4384 1.1938)
			(layers "*.Cu" "*.Mask")
			(remove_unused_layers no)
			(net "GND")
			(clearance 0.127)
			(thermal_gap 0.127)
		)
	)
)
